# BASEBOARD_FAB2 (Tioga Pass) — schematic netlist excerpt (pin names and nets, part order shuffled) for the footprints in the layout excerpt that follows; sources: Cadence DE-HDL packaged netlist, KiCad conversion of Wiwynn_Tioga_Pass_MB.brd

Q8E1  FET_N  2N7002 FET  pkg SOT23LF  page 136
  GATE  = RST_PLTRST_N
  SRC  = GND
  DRN  = RST_PLTRST_TOP_SWAP

R2T49  RES  20.0 1% CHIP  pkg 0402  page 159 : A = SMB_BMC_PMBUS_STBY_LVC3_SDA_R ; B = SMB_BMC_PMBUS_STBY_LVC3_SDA
C2D34  CAP_A  22.0UF 4V 20% X6S  pkg 0603V  page 76 : A = PVCCIN_CPU1 ; B = GND

(kicad_pcb
	(version 20260206)
	(generator "pcbnew")
	(generator_version "10.0")
	(general
		(thickness 1.6)
		(legacy_teardrops no)
	)
	(paper "A4")
	(title_block
		(title "Wiwynn_Tioga_Pass_MB.brd")
		(comment 1 "Tioga Pass / footprints 1270-1272 of 4770")
	)
	(layers
		(0 "F.Cu" signal "TOP")
		(4 "In1.Cu" signal "L2GND")
		(6 "In2.Cu" signal "L3")
		(8 "In3.Cu" signal "L4GND")
		(10 "In4.Cu" signal "L5")
		(12 "In5.Cu" signal "L6GND")
		(14 "In6.Cu" signal "L7VCC")
		(16 "In7.Cu" signal "L8VCC")
		(18 "In8.Cu" signal "L9GND")
		(20 "In9.Cu" signal "L10")
		(22 "In10.Cu" signal "L11GND")
		(24 "In11.Cu" signal "L12")
		(26 "In12.Cu" signal "L13GND")
		(2 "B.Cu" signal "BOTTOM")
		(9 "F.Adhes" user "F.Adhesive")
		(11 "B.Adhes" user "B.Adhesive")
		(13 "F.Paste" user "Package Geometry/Pastemask Top")
		(15 "B.Paste" user "Package Geometry/Pastemask Bottom")
		(5 "F.SilkS" user "Ref Des/Silkscreen Top")
		(7 "B.SilkS" user "Ref Des/Silkscreen Bottom")
		(1 "F.Mask" user "Board Geometry/Soldermask Top")
		(3 "B.Mask" user "Board Geometry/Soldermask Bottom")
		(17 "Dwgs.User" user "User.Drawings")
		(19 "Cmts.User" user "User.Comments")
		(21 "Eco1.User" user "User.Eco1")
		(23 "Eco2.User" user "User.Eco2")
		(25 "Edge.Cuts" user "Board Geometry/Outline")
		(27 "Margin" user)
		(31 "F.CrtYd" user "Package Geometry/Place Bound Top")
		(29 "B.CrtYd" user "Package Geometry/Place Bound Bottom")
		(35 "F.Fab" user "Ref Des/Assembly Top")
		(33 "B.Fab" user "Ref Des/Assembly Bottom")
	)
	(footprint ""
		(layer "F.Cu")
		(at 419.1635 -57.1881)
		(property "Reference" "Q8E1"
			(at 2.1463 0.18669 0)
			(unlocked yes)
			(layer "F.SilkS")
			(effects
				(font
					(size 0.7874 0.5842)
					(thickness 0.1524)
				)
				(justify left)
			)
		)
		(property "Value" ""
			(at 0 0 0)
			(layer "F.Fab")
			(effects
				(font
					(size 1.27 1.27)
				)
			)
		)
		(duplicate_pad_numbers_are_jumpers no)
		(fp_line
			(start 0.381 0.635)
			(end 0.381 1.27)
			(stroke
				(width 0.1524)
				(type default)
			)
			(layer "F.SilkS")
		)
		(fp_line
			(start 0.9525 -0.5715)
			(end 1.778 -0.5715)
			(stroke
				(width 0.1524)
				(type default)
			)
			(layer "F.SilkS")
		)
		(fp_line
			(start 0.9525 2.4765)
			(end 1.778 2.4765)
			(stroke
				(width 0.1524)
				(type default)
			)
			(layer "F.SilkS")
		)
		(fp_line
			(start 1.778 -0.5715)
			(end 1.778 0.3175)
			(stroke
				(width 0.1524)
				(type default)
			)
			(layer "F.SilkS")
		)
		(fp_line
			(start 1.778 2.4765)
			(end 1.778 1.5875)
			(stroke
				(width 0.1524)
				(type default)
			)
			(layer "F.SilkS")
		)
		(fp_circle
			(center -0.636524 -0.804672)
			(end -0.509524 -0.804672)
			(stroke
				(width 0.254)
				(type default)
			)
			(fill no)
			(layer "F.SilkS")
		)
		(fp_poly
			(pts
				(xy 1.778 2.4765) (xy 0.381 2.4765) (xy 0.381 -0.5715) (xy 1.778 -0.5715)
			)
			(stroke
				(width 0)
				(type default)
			)
			(fill no)
			(layer "F.CrtYd")
		)
		(fp_line
			(start 0.381 -0.5715)
			(end 0.381 2.4765)
			(stroke
				(width 0.1)
				(type default)
			)
			(layer "F.Fab")
		)
		(fp_line
			(start 0.381 2.4765)
			(end 1.778 2.4765)
			(stroke
				(width 0.1)
				(type default)
			)
			(layer "F.Fab")
		)
		(fp_line
			(start 1.778 -0.5715)
			(end 0.381 -0.5715)
			(stroke
				(width 0.1)
				(type default)
			)
			(layer "F.Fab")
		)
		(fp_line
			(start 1.778 2.4765)
			(end 1.778 -0.5715)
			(stroke
				(width 0.1)
				(type default)
			)
			(layer "F.Fab")
		)
		(fp_circle
			(center -0.9525 -0.9271)
			(end -0.8255 -0.9271)
			(stroke
				(width 0.254)
				(type default)
			)
			(fill no)
			(layer "F.Fab")
		)
		(pad "1" smd rect
			(at 0 0)
			(size 1.143 0.508)
			(layers "F.Cu" "F.Mask" "F.Paste")
			(net "RST_PLTRST_N")
		)
		(pad "2" smd rect
			(at 0 1.905)
			(size 1.143 0.508)
			(layers "F.Cu" "F.Mask" "F.Paste")
			(net "GND")
		)
		(pad "3" smd rect
			(at 2.159 0.9525)
			(size 1.143 0.508)
			(layers "F.Cu" "F.Mask" "F.Paste")
			(net "RST_PLTRST_TOP_SWAP")
		)
	)
	(footprint ""
		(layer "F.Cu")
		(at 419.862 -21.6535)
		(property "Reference" "R2T49"
			(at 0 0 0)
			(layer "F.SilkS")
			(hide yes)
			(effects
				(font
					(size 1.27 1.27)
				)
			)
		)
		(property "Value" ""
			(at 0 0 0)
			(layer "F.Fab")
			(effects
				(font
					(size 1.27 1.27)
				)
			)
		)
		(duplicate_pad_numbers_are_jumpers no)
		(fp_poly
			(pts
				(xy -0.2794 -0.1016) (xy 0.2794 -0.1016) (xy 0.2794 0.9906) (xy -0.2794 0.9906)
			)
			(stroke
				(width 0)
				(type default)
			)
			(fill no)
			(layer "F.CrtYd")
		)
		(fp_line
			(start -0.2794 -0.1016)
			(end -0.2794 0.9906)
			(stroke
				(width 0.1)
				(type default)
			)
			(layer "F.Fab")
		)
		(fp_line
			(start -0.2794 0.9906)
			(end 0.2794 0.9906)
			(stroke
				(width 0.1)
				(type default)
			)
			(layer "F.Fab")
		)
		(fp_line
			(start 0.2794 -0.1016)
			(end -0.2794 -0.1016)
			(stroke
				(width 0.1)
				(type default)
			)
			(layer "F.Fab")
		)
		(fp_line
			(start 0.2794 0.9906)
			(end 0.2794 -0.1016)
			(stroke
				(width 0.1)
				(type default)
			)
			(layer "F.Fab")
		)
		(pad "1" smd rect
			(at 0 0)
			(size 0.508 0.508)
			(layers "F.Cu" "F.Mask" "F.Paste")
			(net "SMB_BMC_PMBUS_STBY_LVC3_SDA_R")
		)
		(pad "2" smd rect
			(at 0 0.889)
			(size 0.508 0.508)
			(layers "F.Cu" "F.Mask" "F.Paste")
			(net "SMB_BMC_PMBUS_STBY_LVC3_SDA")
		)
		(zone
			(layer "F.Cu")
			(hatch none 0.5)
			(connect_pads
				(clearance 0)
			)
			(min_thickness 0.25)
			(keepout
				(tracks allowed)
				(vias not_allowed)
				(pads allowed)
				(copperpour not_allowed)
				(footprints allowed)
			)
			(placement
				(enabled no)
				(sheetname "")
			)
			(fill
				(thermal_gap 0.5)
				(thermal_bridge_width 0.5)
				(island_removal_mode 0)
			)
			(polygon
				(pts
					(xy 419.608 -21.3995) (xy 420.116 -21.3995) (xy 420.116 -21.0185) (xy 419.608 -21.0185)
				)
			)
		)
		(zone
			(layer "F.Cu")
			(hatch none 0.5)
			(connect_pads
				(clearance 0)
			)
			(min_thickness 0.25)
			(keepout
				(tracks not_allowed)
				(vias allowed)
				(pads allowed)
				(copperpour not_allowed)
				(footprints allowed)
			)
			(placement
				(enabled no)
				(sheetname "")
			)
			(fill
				(thermal_gap 0.5)
				(thermal_bridge_width 0.5)
				(island_removal_mode 0)
			)
			(polygon
				(pts
					(xy 419.608 -21.0185) (xy 420.116 -21.0185) (xy 420.116 -21.3995) (xy 419.608 -21.3995)
				)
			)
		)
	)
	(footprint ""
		(layer "F.Cu")
		(at 98.18624 -73.318116)
		(property "Reference" "C2D34"
			(at 0 0 0)
			(layer "F.SilkS")
			(hide yes)
			(effects
				(font
					(size 1.27 1.27)
				)
			)
		)
		(property "Value" ""
			(at 0 0 0)
			(layer "F.Fab")
			(effects
				(font
					(size 1.27 1.27)
				)
			)
		)
		(duplicate_pad_numbers_are_jumpers no)
		(fp_poly
			(pts
				(xy -0.4953 -0.2032) (xy 0.4953 -0.2032) (xy 0.4953 1.6002) (xy -0.4953 1.6002)
			)
			(stroke
				(width 0)
				(type default)
			)
			(fill no)
			(layer "F.CrtYd")
		)
		(fp_line
			(start -0.4953 -0.2032)
			(end 0.4953 -0.2032)
			(stroke
				(width 0.1)
				(type default)
			)
			(layer "F.Fab")
		)
		(fp_line
			(start -0.4953 1.6002)
			(end -0.4953 -0.2032)
			(stroke
				(width 0.1)
				(type default)
			)
			(layer "F.Fab")
		)
		(fp_line
			(start 0.4953 -0.2032)
			(end 0.4953 1.6002)
			(stroke
				(width 0.1)
				(type default)
			)
			(layer "F.Fab")
		)
		(fp_line
			(start 0.4953 1.6002)
			(end -0.4953 1.6002)
			(stroke
				(width 0.1)
				(type default)
			)
			(layer "F.Fab")
		)
		(pad "1" smd rect
			(at 0 0)
			(size 0.762 0.889)
			(layers "F.Cu" "F.Mask" "F.Paste")
			(net "PVCCIN_CPU1")
		)
		(pad "2" smd rect
			(at 0 1.397)
			(size 0.762 0.889)
			(layers "F.Cu" "F.Mask" "F.Paste")
			(net "GND")
		)
		(zone
			(layer "F.Cu")
			(hatch none 0.5)
			(connect_pads
				(clearance 0)
			)
			(min_thickness 0.25)
			(keepout
				(tracks not_allowed)
				(vias allowed)
				(pads allowed)
				(copperpour not_allowed)
				(footprints allowed)
			)
			(placement
				(enabled no)
				(sheetname "")
			)
			(fill
				(thermal_gap 0.5)
				(thermal_bridge_width 0.5)
				(island_removal_mode 0)
			)
			(polygon
				(pts
					(xy 97.80524 -72.873616) (xy 98.56724 -72.873616) (xy 98.56724 -72.365616) (xy 97.80524 -72.365616)
				)
			)
		)
	)
)
